(kicad_pcb
	(version 20221018)
	(generator pcbnew)
	(general
    (thickness 1.562)
  )
	(paper "A4")
	(title_block
    (title "Thunderbolt PCIe Adaper")
    (date "2024-07-09")
    (rev "1.0.3")
    (comment 1 "www.antmicro.com")
    (comment 2 "Antmicro Ltd.")
		(comment 9 "footprints 202-210 of 271")
	)
	(layers
    (0 "F.Cu" signal)
    (1 "In1.Cu" signal)
    (2 "In2.Cu" signal)
    (3 "In3.Cu" signal)
    (4 "In4.Cu" signal)
    (31 "B.Cu" signal)
    (32 "B.Adhes" user "B.Adhesive")
    (33 "F.Adhes" user "F.Adhesive")
    (34 "B.Paste" user)
    (35 "F.Paste" user)
    (36 "B.SilkS" user "B.Silkscreen")
    (37 "F.SilkS" user "F.Silkscreen")
    (38 "B.Mask" user)
    (39 "F.Mask" user)
    (40 "Dwgs.User" user "User.Drawings")
    (41 "Cmts.User" user "User.Comments")
    (42 "Eco1.User" user "User.Eco1")
    (43 "Eco2.User" user "User.Eco2")
    (44 "Edge.Cuts" user)
    (45 "Margin" user)
    (46 "B.CrtYd" user "B.Courtyard")
    (47 "F.CrtYd" user "F.Courtyard")
    (48 "B.Fab" user)
    (49 "F.Fab" user)
  )
	(footprint "antmicro-footprints:C_0402_1005Metric" (layer "B.Cu")
    (at 133.325 83.75 90)
    (descr "Capacitor SMD 0402")
    (tags "capacitor SMD 0402")
    (property "Author" "Antmicro")
    (property "Dielectric" "")
    (property "License" "Apache-2.0")
    (property "MPN" "C1005X6S1A105K050BC")
    (property "Manufacturer" "TDK")
    (property "Sheetfile" "tb-power.kicad_sch")
    (property "Sheetname" "Thunderbolt Controller - Power")
    (property "Val" "1u")
    (property "Voltage" "")
    (property "ki_description" "SMD Multilayer Ceramic Capacitor, 1 µF, 10 V, 0402 [1005 Metric], ± 10%, X6S, C")
    (property "ki_keywords" "0402, SMT, CAPACITOR, PASSIVE, CERAMIC, MLCC")
    (attr smd)
    (fp_text reference "C52" (at -5.912 16.916 270) (layer "B.SilkS")
        (effects (font (size 0.7 0.7) (thickness 0.15)) (justify left bottom mirror))
    )
    (fp_text value "C_1u_0402" (at -1.022927 -2.155213 270) (layer "B.Fab")
        (effects (font (size 0.7 0.7) (thickness 0.15)) (justify left bottom mirror))
    )
    (fp_text user "Author: Antmicro" (at -0.939 -3.399 270) (layer "B.Fab") hide
        (effects (font (size 0.7 0.7) (thickness 0.15)) (justify left bottom mirror))
    )
    (fp_text user "${REFERENCE}" (at -0.939 -4.599 270) (layer "B.Fab") hide
        (effects (font (size 0.7 0.7) (thickness 0.15)) (justify left bottom mirror))
    )
    (fp_text user "License: Apache-2.0" (at -0.939 -5.799 270) (layer "B.Fab") hide
        (effects (font (size 0.7 0.7) (thickness 0.15)) (justify left bottom mirror))
    )
    (fp_rect (start -0.925 0.47) (end 0.925 -0.47)
      (stroke (width 0.05) (type default)) (fill none) (layer "B.CrtYd"))
    (fp_line (start -0.494 -0.248) (end -0.494 0.25)
      (stroke (width 0.15) (type solid)) (layer "B.Fab"))
    (fp_line (start -0.494 0.25) (end 0.504 0.25)
      (stroke (width 0.15) (type solid)) (layer "B.Fab"))
    (fp_line (start 0.504 -0.248) (end -0.494 -0.248)
      (stroke (width 0.15) (type solid)) (layer "B.Fab"))
    (fp_line (start 0.504 0.25) (end 0.504 -0.248)
      (stroke (width 0.15) (type solid)) (layer "B.Fab"))
    (pad "1" smd roundrect (at -0.48 0 90) (size 0.59 0.64) (layers "B.Cu" "B.Paste" "B.Mask") (roundrect_rratio 0.25)
      (net 1 "GND") (pintype "passive"))
    (pad "2" smd roundrect (at 0.48 0 90) (size 0.59 0.64) (layers "B.Cu" "B.Paste" "B.Mask") (roundrect_rratio 0.25)
      (net 105 "Net-(C51-Pad2)") (pintype "passive"))
  )
	(footprint "antmicro-footprints:Fiducial_1mm_Mask3mm" (layer "B.Cu")
    (at 161 98 180)
    (descr "Circular Fiducial, 1.5mm bare copper, 3mm soldermask opening")
    (tags "fiducial")
    (property "Author" "Antmicro")
    (property "License" "Apache-2.0")
    (property "Sheetfile" "thunderbolt-pcie-adapter.kicad_sch")
    (property "Sheetname" "")
    (property "exclude_from_bom" "")
    (property "ki_description" "Fiducial mask")
    (attr through_hole exclude_from_bom)
    (fp_text reference "FID8" (at 1.742 -0.425) (layer "B.SilkS")
        (effects (font (size 0.7 0.7) (thickness 0.15)) (justify left bottom mirror))
    )
    (fp_text value "Fiducial_1mm_Mask3mm" (at 0 -2.603) (layer "B.Fab")
        (effects (font (size 0.7 0.7) (thickness 0.15)) (justify left bottom mirror))
    )
    (fp_text user "License: Apache-2.0" (at -1.25 -7.003) (layer "B.Fab") hide
        (effects (font (size 0.7 0.7) (thickness 0.15)) (justify left bottom mirror))
    )
    (fp_text user "Author: Antmicro" (at -1.25 -5.803) (layer "B.Fab") hide
        (effects (font (size 0.7 0.7) (thickness 0.15)) (justify left bottom mirror))
    )
    (fp_text user "${REFERENCE}" (at -1.25 -4.603) (layer "B.Fab") hide
        (effects (font (size 0.7 0.7) (thickness 0.15)) (justify left bottom mirror))
    )
    (fp_circle (center 0 0) (end 1.5 0)
      (stroke (width 0.05) (type solid)) (fill none) (layer "B.CrtYd"))
    (fp_circle (center 0 0) (end 1.5 0)
      (stroke (width 0.15) (type solid)) (fill none) (layer "B.Fab"))
    (pad "" smd circle (at 0 0 180) (size 1 1) (layers "B.Cu" "B.Mask")
      (solder_mask_margin 1) (clearance 1))
  )
	(footprint "antmicro-footprints:C_0402_1005Metric" (layer "B.Cu")
    (at 140.16 80.336001 90)
    (descr "Capacitor SMD 0402")
    (tags "capacitor SMD 0402")
    (property "Author" "Antmicro")
    (property "Dielectric" "")
    (property "License" "Apache-2.0")
    (property "MPN" "CC0402MRX5R5BB106")
    (property "Manufacturer" "YAGEO")
    (property "Sheetfile" "tb-power.kicad_sch")
    (property "Sheetname" "Thunderbolt Controller - Power")
    (property "Val" "10u")
    (property "Voltage" "")
    (property "ki_description" "SMD Multilayer Ceramic Capacitor, 10 µF, 6.3 V, 0402 [1005 Metric], ± 20%, X5R, CC Series")
    (property "ki_keywords" "0402, SMT, CAPACITOR, PASSIVE, MLCC, CERAMIC")
    (attr smd)
    (fp_text reference "C78" (at -6.658999 17.066 270) (layer "B.SilkS")
        (effects (font (size 0.7 0.7) (thickness 0.15)) (justify left bottom mirror))
    )
    (fp_text value "C_10u_0402" (at -1.022927 -2.155213 270) (layer "B.Fab")
        (effects (font (size 0.7 0.7) (thickness 0.15)) (justify left bottom mirror))
    )
    (fp_text user "${REFERENCE}" (at -0.939 -4.599 270) (layer "B.Fab") hide
        (effects (font (size 0.7 0.7) (thickness 0.15)) (justify left bottom mirror))
    )
    (fp_text user "License: Apache-2.0" (at -0.939 -5.799 270) (layer "B.Fab") hide
        (effects (font (size 0.7 0.7) (thickness 0.15)) (justify left bottom mirror))
    )
    (fp_text user "Author: Antmicro" (at -0.939 -3.399 270) (layer "B.Fab") hide
        (effects (font (size 0.7 0.7) (thickness 0.15)) (justify left bottom mirror))
    )
    (fp_rect (start -0.925 0.47) (end 0.925 -0.47)
      (stroke (width 0.05) (type default)) (fill none) (layer "B.CrtYd"))
    (fp_line (start -0.494 -0.248) (end -0.494 0.25)
      (stroke (width 0.15) (type solid)) (layer "B.Fab"))
    (fp_line (start -0.494 0.25) (end 0.504 0.25)
      (stroke (width 0.15) (type solid)) (layer "B.Fab"))
    (fp_line (start 0.504 -0.248) (end -0.494 -0.248)
      (stroke (width 0.15) (type solid)) (layer "B.Fab"))
    (fp_line (start 0.504 0.25) (end 0.504 -0.248)
      (stroke (width 0.15) (type solid)) (layer "B.Fab"))
    (pad "1" smd roundrect (at -0.48 0 90) (size 0.59 0.64) (layers "B.Cu" "B.Paste" "B.Mask") (roundrect_rratio 0.25)
      (net 1 "GND") (pintype "passive"))
    (pad "2" smd roundrect (at 0.48 0 90) (size 0.59 0.64) (layers "B.Cu" "B.Paste" "B.Mask") (roundrect_rratio 0.25)
      (net 113 "Net-(U4A-VCC0P9_LVR_SENSE)") (pintype "passive"))
  )
	(footprint "antmicro-footprints:C_0402_1005Metric" (layer "B.Cu")
    (at 157.91 59.47 -90)
    (descr "Capacitor SMD 0402")
    (tags "capacitor SMD 0402")
    (property "Author" "Antmicro")
    (property "Dielectric" "X5S")
    (property "License" "Apache-2.0")
    (property "MPN" "GRM155C61E475ME15J")
    (property "Manufacturer" "Murata")
    (property "Sheetfile" "power.kicad_sch")
    (property "Sheetname" "Power")
    (property "Val" "4u7")
    (property "Voltage" "25V")
    (property "dnp" "")
    (property "ki_description" "SMD Multilayer Ceramic Capacitor")
    (property "ki_keywords" "0402, SMT, CAPACITOR, PASSIVE, CERAMIC")
    (attr smd)
    (fp_text reference "C20" (at -4.86 5.51 90) (layer "B.SilkS")
        (effects (font (size 0.7 0.7) (thickness 0.15)) (justify left bottom mirror))
    )
    (fp_text value "C_4u7_25V_0402" (at -1.022927 -2.155213 90) (layer "B.Fab")
        (effects (font (size 0.7 0.7) (thickness 0.15)) (justify left bottom mirror))
    )
    (fp_text user "Author: Antmicro" (at -0.939 -3.399 90) (layer "B.Fab") hide
        (effects (font (size 0.7 0.7) (thickness 0.15)) (justify left bottom mirror))
    )
    (fp_text user "License: Apache-2.0" (at -0.939 -5.799 90) (layer "B.Fab") hide
        (effects (font (size 0.7 0.7) (thickness 0.15)) (justify left bottom mirror))
    )
    (fp_text user "${REFERENCE}" (at -0.939 -4.599 90) (layer "B.Fab") hide
        (effects (font (size 0.7 0.7) (thickness 0.15)) (justify left bottom mirror))
    )
    (fp_rect (start -0.925 0.47) (end 0.925 -0.47)
      (stroke (width 0.05) (type default)) (fill none) (layer "B.CrtYd"))
    (fp_line (start -0.494 -0.248) (end -0.494 0.25)
      (stroke (width 0.15) (type solid)) (layer "B.Fab"))
    (fp_line (start -0.494 0.25) (end 0.504 0.25)
      (stroke (width 0.15) (type solid)) (layer "B.Fab"))
    (fp_line (start 0.504 -0.248) (end -0.494 -0.248)
      (stroke (width 0.15) (type solid)) (layer "B.Fab"))
    (fp_line (start 0.504 0.25) (end 0.504 -0.248)
      (stroke (width 0.15) (type solid)) (layer "B.Fab"))
    (pad "1" smd roundrect (at -0.48 0 270) (size 0.59 0.64) (layers "B.Cu" "B.Paste" "B.Mask") (roundrect_rratio 0.25)
      (net 1 "GND") (pintype "passive"))
    (pad "2" smd roundrect (at 0.48 0 270) (size 0.59 0.64) (layers "B.Cu" "B.Paste" "B.Mask") (roundrect_rratio 0.25)
      (net 19 "PP_HV") (pintype "passive"))
  )
	(footprint "antmicro-footprints:C_0402_1005Metric" (layer "B.Cu")
    (at 136.275 80.35 -90)
    (descr "Capacitor SMD 0402")
    (tags "capacitor SMD 0402")
    (property "Author" "Antmicro")
    (property "Dielectric" "")
    (property "License" "Apache-2.0")
    (property "MPN" "C1005X6S1A105K050BC")
    (property "Manufacturer" "TDK")
    (property "Sheetfile" "tb-power.kicad_sch")
    (property "Sheetname" "Thunderbolt Controller - Power")
    (property "Val" "1u")
    (property "Voltage" "")
    (property "ki_description" "SMD Multilayer Ceramic Capacitor, 1 µF, 10 V, 0402 [1005 Metric], ± 10%, X6S, C")
    (property "ki_keywords" "0402, SMT, CAPACITOR, PASSIVE, CERAMIC, MLCC")
    (attr smd)
    (fp_text reference "C66" (at 6.518 -16.887 90) (layer "B.SilkS")
        (effects (font (size 0.7 0.7) (thickness 0.15)) (justify left bottom mirror))
    )
    (fp_text value "C_1u_0402" (at -1.022927 -2.155213 90) (layer "B.Fab")
        (effects (font (size 0.7 0.7) (thickness 0.15)) (justify left bottom mirror))
    )
    (fp_text user "License: Apache-2.0" (at -0.939 -5.799 90) (layer "B.Fab") hide
        (effects (font (size 0.7 0.7) (thickness 0.15)) (justify left bottom mirror))
    )
    (fp_text user "${REFERENCE}" (at -0.939 -4.599 90) (layer "B.Fab") hide
        (effects (font (size 0.7 0.7) (thickness 0.15)) (justify left bottom mirror))
    )
    (fp_text user "Author: Antmicro" (at -0.939 -3.399 90) (layer "B.Fab") hide
        (effects (font (size 0.7 0.7) (thickness 0.15)) (justify left bottom mirror))
    )
    (fp_rect (start -0.925 0.47) (end 0.925 -0.47)
      (stroke (width 0.05) (type default)) (fill none) (layer "B.CrtYd"))
    (fp_line (start -0.494 -0.248) (end -0.494 0.25)
      (stroke (width 0.15) (type solid)) (layer "B.Fab"))
    (fp_line (start -0.494 0.25) (end 0.504 0.25)
      (stroke (width 0.15) (type solid)) (layer "B.Fab"))
    (fp_line (start 0.504 -0.248) (end -0.494 -0.248)
      (stroke (width 0.15) (type solid)) (layer "B.Fab"))
    (fp_line (start 0.504 0.25) (end 0.504 -0.248)
      (stroke (width 0.15) (type solid)) (layer "B.Fab"))
    (pad "1" smd roundrect (at -0.48 0 270) (size 0.59 0.64) (layers "B.Cu" "B.Paste" "B.Mask") (roundrect_rratio 0.25)
      (net 1 "GND") (pintype "passive"))
    (pad "2" smd roundrect (at 0.48 0 270) (size 0.59 0.64) (layers "B.Cu" "B.Paste" "B.Mask") (roundrect_rratio 0.25)
      (net 109 "Net-(U4A-VCC3P3_ANA_PCIE)") (pintype "passive"))
  )
	(footprint "antmicro-footprints:R_0402_1005Metric" (layer "B.Cu")
    (at 114.430001 63.675 90)
    (descr "Resistor SMD 0402")
    (tags "resistor SMD 0402")
    (property "Author" "Antmicro")
    (property "License" "Apache-2.0")
    (property "MPN" "CR0402-FX-1002GLF")
    (property "Manufacturer" "Bourns")
    (property "Sheetfile" "power.kicad_sch")
    (property "Sheetname" "Power")
    (property "Tolerance" "1%")
    (property "Val" "10k")
    (property "ki_description" "SMD Chip Resistor, 10 kohm, ± 1%, 62.5 mW, 0402 [1005 Metric], Thick Film, General Purpose")
    (property "ki_keywords" "0402, SMT, RESISTOR, PASSIVE")
    (attr smd)
    (fp_text reference "R6" (at -0.435 -0.580001 90) (layer "B.SilkS")
        (effects (font (size 0.7 0.7) (thickness 0.15)) (justify right bottom mirror))
    )
    (fp_text value "R_10k_0402" (at -1.011843 -1.772047 90) (layer "B.Fab")
        (effects (font (size 0.7 0.7) (thickness 0.15)) (justify right bottom mirror))
    )
    (fp_text user "License: Apache-2.0" (at -0.95 -5.169 90) (layer "B.Fab") hide
        (effects (font (size 0.7 0.7) (thickness 0.15)) (justify right bottom mirror))
    )
    (fp_text user "${REFERENCE}" (at -0.95 -3.168 90) (layer "B.Fab") hide
        (effects (font (size 0.7 0.7) (thickness 0.15)) (justify right bottom mirror))
    )
    (fp_text user "Author: Antmicro" (at -0.95 -4.169 90) (layer "B.Fab") hide
        (effects (font (size 0.7 0.7) (thickness 0.15)) (justify right bottom mirror))
    )
    (fp_rect (start -0.925 0.47) (end 0.925 -0.47)
      (stroke (width 0.05) (type default)) (fill none) (layer "B.CrtYd"))
    (fp_rect (start -0.5 0.25) (end 0.5 -0.25)
      (stroke (width 0.15) (type solid)) (fill none) (layer "B.Fab"))
    (pad "1" smd roundrect (at -0.48 0 90) (size 0.59 0.64) (layers "B.Cu" "B.Paste" "B.Mask") (roundrect_rratio 0.25)
      (net 90 "Net-(U2-VIN)") (pintype "passive"))
    (pad "2" smd roundrect (at 0.48 0 90) (size 0.59 0.64) (layers "B.Cu" "B.Paste" "B.Mask") (roundrect_rratio 0.25)
      (net 119 "Net-(D1-C)") (pintype "passive"))
  )
	(footprint "antmicro-footprints:R_0402_1005Metric" (layer "B.Cu")
    (at 142.35 66.82 90)
    (descr "Resistor SMD 0402")
    (tags "resistor SMD 0402")
    (property "Author" "Antmicro")
    (property "License" "Apache-2.0")
    (property "MPN" "CR0402-FX-1003GLF")
    (property "Manufacturer" "Bourns")
    (property "Sheetfile" "tb.kicad_sch")
    (property "Sheetname" "TB Controller")
    (property "Tolerance" "1%")
    (property "Val" "100k")
    (property "ki_description" "SMD Chip Resistor, 100 kohm, ± 1%, 62.5 mW, 0402 [1005 Metric], Thick Film, General Purpose")
    (property "ki_keywords" "0402, SMT, RESISTOR, PASSIVE")
    (attr smd)
    (fp_text reference "R84" (at 3.066 0.398 270) (layer "B.SilkS")
        (effects (font (size 0.7 0.7) (thickness 0.15)) (justify left bottom mirror))
    )
    (fp_text value "R_100k_0402" (at -1.011843 -1.772047 270) (layer "B.Fab")
        (effects (font (size 0.7 0.7) (thickness 0.15)) (justify left bottom mirror))
    )
    (fp_text user "${REFERENCE}" (at -0.95 -3.168 270) (layer "B.Fab") hide
        (effects (font (size 0.7 0.7) (thickness 0.15)) (justify left bottom mirror))
    )
    (fp_text user "Author: Antmicro" (at -0.95 -4.169 270) (layer "B.Fab") hide
        (effects (font (size 0.7 0.7) (thickness 0.15)) (justify left bottom mirror))
    )
    (fp_text user "License: Apache-2.0" (at -0.95 -5.169 270) (layer "B.Fab") hide
        (effects (font (size 0.7 0.7) (thickness 0.15)) (justify left bottom mirror))
    )
    (fp_rect (start -0.925 0.47) (end 0.925 -0.47)
      (stroke (width 0.05) (type default)) (fill none) (layer "B.CrtYd"))
    (fp_rect (start -0.5 0.25) (end 0.5 -0.25)
      (stroke (width 0.15) (type solid)) (fill none) (layer "B.Fab"))
    (pad "1" smd roundrect (at -0.48 0 90) (size 0.59 0.64) (layers "B.Cu" "B.Paste" "B.Mask") (roundrect_rratio 0.25)
      (net 199 "Net-(U4C-POC_GPIO_2)") (pintype "passive"))
    (pad "2" smd roundrect (at 0.48 0 90) (size 0.59 0.64) (layers "B.Cu" "B.Paste" "B.Mask") (roundrect_rratio 0.25)
      (net 1 "GND") (pintype "passive"))
  )
	(footprint "antmicro-footprints:R_0402_1005Metric" (layer "B.Cu")
    (at 106.955 82.660001)
    (descr "Resistor SMD 0402")
    (tags "resistor SMD 0402")
    (property "Author" "Antmicro")
    (property "License" "Apache-2.0")
    (property "MPN" "CR0402-FX-1002GLF")
    (property "Manufacturer" "Bourns")
    (property "Sheetfile" "power.kicad_sch")
    (property "Sheetname" "Power")
    (property "Tolerance" "1%")
    (property "Val" "10k")
    (property "ki_description" "SMD Chip Resistor, 10 kohm, ± 1%, 62.5 mW, 0402 [1005 Metric], Thick Film, General Purpose")
    (property "ki_keywords" "0402, SMT, RESISTOR, PASSIVE")
    (attr smd)
    (fp_text reference "R8" (at -0.91 0.397999 180) (layer "B.SilkS")
        (effects (font (size 0.7 0.7) (thickness 0.15)) (justify left bottom mirror))
    )
    (fp_text value "R_10k_0402" (at -1.011843 -1.772047 180) (layer "B.Fab")
        (effects (font (size 0.7 0.7) (thickness 0.15)) (justify left bottom mirror))
    )
    (fp_text user "${REFERENCE}" (at -0.95 -3.168 180) (layer "B.Fab") hide
        (effects (font (size 0.7 0.7) (thickness 0.15)) (justify left bottom mirror))
    )
    (fp_text user "License: Apache-2.0" (at -0.95 -5.169 180) (layer "B.Fab") hide
        (effects (font (size 0.7 0.7) (thickness 0.15)) (justify left bottom mirror))
    )
    (fp_text user "Author: Antmicro" (at -0.95 -4.169 180) (layer "B.Fab") hide
        (effects (font (size 0.7 0.7) (thickness 0.15)) (justify left bottom mirror))
    )
    (fp_rect (start -0.925 0.47) (end 0.925 -0.47)
      (stroke (width 0.05) (type default)) (fill none) (layer "B.CrtYd"))
    (fp_rect (start -0.5 0.25) (end 0.5 -0.25)
      (stroke (width 0.15) (type solid)) (fill none) (layer "B.Fab"))
    (pad "1" smd roundrect (at -0.48 0) (size 0.59 0.64) (layers "B.Cu" "B.Paste" "B.Mask") (roundrect_rratio 0.25)
      (net 1 "GND") (pintype "passive"))
    (pad "2" smd roundrect (at 0.48 0) (size 0.59 0.64) (layers "B.Cu" "B.Paste" "B.Mask") (roundrect_rratio 0.25)
      (net 88 "/Power/DCDC_EN") (pintype "passive"))
  )
	(footprint "antmicro-footprints:R_0402_1005Metric" (layer "B.Cu")
    (at 116.910001 62.205 180)
    (descr "Resistor SMD 0402")
    (tags "resistor SMD 0402")
    (property "Author" "Antmicro")
    (property "License" "Apache-2.0")
    (property "MPN" "CR0402-FX-8871GLF")
    (property "Manufacturer" "Bourns")
    (property "Sheetfile" "power.kicad_sch")
    (property "Sheetname" "Power")
    (property "Tolerance" "1%")
    (property "Val" "8k87")
    (property "ki_description" "SMD Chip Resistor, 8.87 kohm, ± 1%, 100 mW, 0402 [1005 Metric], Thick Film, Precision")
    (property "ki_keywords" "0402, SMT, RESISTOR, PASSIVE")
    (attr smd)
    (fp_text reference "R37" (at -3.104999 -0.406) (layer "B.SilkS")
        (effects (font (size 0.7 0.7) (thickness 0.15)) (justify left bottom mirror))
    )
    (fp_text value "R_8k87_0402" (at -1.011843 -1.772047) (layer "B.Fab")
        (effects (font (size 0.7 0.7) (thickness 0.15)) (justify left bottom mirror))
    )
    (fp_text user "License: Apache-2.0" (at -0.95 -5.169) (layer "B.Fab") hide
        (effects (font (size 0.7 0.7) (thickness 0.15)) (justify left bottom mirror))
    )
    (fp_text user "Author: Antmicro" (at -0.95 -4.169) (layer "B.Fab") hide
        (effects (font (size 0.7 0.7) (thickness 0.15)) (justify left bottom mirror))
    )
    (fp_text user "${REFERENCE}" (at -0.95 -3.168) (layer "B.Fab") hide
        (effects (font (size 0.7 0.7) (thickness 0.15)) (justify left bottom mirror))
    )
    (fp_rect (start -0.925 0.47) (end 0.925 -0.47)
      (stroke (width 0.05) (type default)) (fill none) (layer "B.CrtYd"))
    (fp_rect (start -0.5 0.25) (end 0.5 -0.25)
      (stroke (width 0.15) (type solid)) (fill none) (layer "B.Fab"))
    (pad "1" smd roundrect (at -0.48 0 180) (size 0.59 0.64) (layers "B.Cu" "B.Paste" "B.Mask") (roundrect_rratio 0.25)
      (net 1 "GND") (pintype "passive"))
    (pad "2" smd roundrect (at 0.48 0 180) (size 0.59 0.64) (layers "B.Cu" "B.Paste" "B.Mask") (roundrect_rratio 0.25)
      (net 99 "Net-(U2-FB)") (pintype "passive"))
  )
)
